# S9S_MB_2U (Grand Teton) — schematic netlist excerpt (pin names and nets, part order shuffled) for the footprints in the layout excerpt that follows; sources: Cadence DE-HDL packaged netlist, KiCad conversion of 03242023_DA0F0TMBIJ0_F0T_Motherboard_J_brd_V01_OCP.brd

C984  Q_CAP  10UF 6.3V 20% X6S  pkg C0402  page 74 : A = PVCCIN_CPU0 ; B = GND
C916  Q_CAP_DIFFBUS  DIFF BUS_0.22UF 6.3V 20% X6S  pkg C0201  page 173 : \1\ = P5E_CPU0_PE0_TX_C_DN<8> ; \2\ = P5E_CPU0_PE0_TX_DN<8>
PR3971  Q_RES  9.76K 1% CHIP  pkg 0402LF  page 192 : A = P3V3_E1S_SENSE_0 ; B = GND

(kicad_pcb
	(version 20260206)
	(generator "pcbnew")
	(generator_version "10.0")
	(general
		(thickness 1.6)
		(legacy_teardrops no)
	)
	(paper "A4")
	(title_block
		(title "03242023_DA0F0TMBIJ0_F0T_Motherboard_J_brd_V01_OCP.brd")
		(comment 1 "Grand Teton / footprints 1657-1659 of 6105")
	)
	(layers
		(0 "F.Cu" signal "TOP")
		(4 "In1.Cu" signal "GND")
		(6 "In2.Cu" signal "IN1")
		(8 "In3.Cu" signal "GND1")
		(10 "In4.Cu" signal "IN2")
		(12 "In5.Cu" signal "GND2")
		(14 "In6.Cu" signal "IN3")
		(16 "In7.Cu" signal "GND3")
		(18 "In8.Cu" signal "VCC")
		(20 "In9.Cu" signal "VCC1")
		(22 "In10.Cu" signal "GND4")
		(24 "In11.Cu" signal "IN4")
		(26 "In12.Cu" signal "GND5")
		(28 "In13.Cu" signal "IN5")
		(30 "In14.Cu" signal "GND6")
		(32 "In15.Cu" signal "IN6")
		(34 "In16.Cu" signal "GND7")
		(2 "B.Cu" signal "BOTTOM")
		(9 "F.Adhes" user "F.Adhesive")
		(11 "B.Adhes" user "B.Adhesive")
		(13 "F.Paste" user "Package Geometry/Pastemask Top")
		(15 "B.Paste" user "Package Geometry/Pastemask Bottom")
		(5 "F.SilkS" user "Ref Des/Silkscreen Top")
		(7 "B.SilkS" user "Ref Des/Silkscreen Bottom")
		(1 "F.Mask" user "Board Geometry/Soldermask Top")
		(3 "B.Mask" user "Board Geometry/Soldermask Bottom")
		(17 "Dwgs.User" user "User.Drawings")
		(19 "Cmts.User" user "User.Comments")
		(21 "Eco1.User" user "User.Eco1")
		(23 "Eco2.User" user "User.Eco2")
		(25 "Edge.Cuts" user "Board Geometry/Outline")
		(27 "Margin" user)
		(31 "F.CrtYd" user "Package Geometry/Place Bound Top")
		(29 "B.CrtYd" user "Package Geometry/Place Bound Bottom")
		(35 "F.Fab" user "Ref Des/Assembly Top")
		(33 "B.Fab" user "Ref Des/Assembly Bottom")
	)
	(footprint ""
		(layer "F.Cu")
		(at 218.011502 -72.015858 180)
		(property "Reference" "PR3971"
			(at 0 0 180)
			(layer "F.SilkS")
			(hide yes)
			(effects
				(font
					(size 1.27 1.27)
				)
			)
		)
		(property "Value" ""
			(at 0 0 180)
			(layer "F.Fab")
			(effects
				(font
					(size 1.27 1.27)
				)
			)
		)
		(duplicate_pad_numbers_are_jumpers no)
		(fp_line
			(start 0.7874 0.4064)
			(end -0.7874 0.4064)
			(stroke
				(width 0.1524)
				(type default)
			)
			(layer "F.SilkS")
		)
		(fp_line
			(start 0.7874 -0.4064)
			(end 0.7874 0.4064)
			(stroke
				(width 0.1524)
				(type default)
			)
			(layer "F.SilkS")
		)
		(fp_line
			(start -0.7874 0.4064)
			(end -0.7874 -0.4064)
			(stroke
				(width 0.1524)
				(type default)
			)
			(layer "F.SilkS")
		)
		(fp_line
			(start -0.7874 -0.4064)
			(end 0.7874 -0.4064)
			(stroke
				(width 0.1524)
				(type default)
			)
			(layer "F.SilkS")
		)
		(fp_line
			(start 0.67945 0.3048)
			(end 0.120396 0.3048)
			(stroke
				(width 0.1)
				(type default)
			)
			(layer "F.Fab")
		)
		(fp_line
			(start 0.67945 -0.3048)
			(end 0.67945 0.3048)
			(stroke
				(width 0.1)
				(type default)
			)
			(layer "F.Fab")
		)
		(fp_line
			(start 0.12065 -0.2794)
			(end 0.12065 -0.3048)
			(stroke
				(width 0.1)
				(type default)
			)
			(layer "F.Fab")
		)
		(fp_line
			(start 0.12065 -0.3048)
			(end 0.67945 -0.3048)
			(stroke
				(width 0.1)
				(type default)
			)
			(layer "F.Fab")
		)
		(fp_line
			(start 0.120396 0.3048)
			(end 0.120396 0.2794)
			(stroke
				(width 0.1)
				(type default)
			)
			(layer "F.Fab")
		)
		(fp_line
			(start 0.120396 0.2794)
			(end -0.12065 0.2794)
			(stroke
				(width 0.1)
				(type default)
			)
			(layer "F.Fab")
		)
		(fp_line
			(start -0.12065 0.3048)
			(end -0.67945 0.3048)
			(stroke
				(width 0.1)
				(type default)
			)
			(layer "F.Fab")
		)
		(fp_line
			(start -0.12065 0.2794)
			(end -0.12065 0.3048)
			(stroke
				(width 0.1)
				(type default)
			)
			(layer "F.Fab")
		)
		(fp_line
			(start -0.12065 -0.2794)
			(end 0.12065 -0.2794)
			(stroke
				(width 0.1)
				(type default)
			)
			(layer "F.Fab")
		)
		(fp_line
			(start -0.12065 -0.305054)
			(end -0.12065 -0.2794)
			(stroke
				(width 0.1)
				(type default)
			)
			(layer "F.Fab")
		)
		(fp_line
			(start -0.67945 0.3048)
			(end -0.67945 -0.305054)
			(stroke
				(width 0.1)
				(type default)
			)
			(layer "F.Fab")
		)
		(fp_line
			(start -0.67945 -0.305054)
			(end -0.12065 -0.305054)
			(stroke
				(width 0.1)
				(type default)
			)
			(layer "F.Fab")
		)
		(pad "1" smd circle
			(at -0.40005 0 180)
			(size 0 0)
			(layers "F.Cu" "F.Mask" "F.Paste")
			(net "P3V3_E1S_SENSE_0")
		)
		(pad "2" smd circle
			(at 0.40005 0 180)
			(size 0 0)
			(layers "F.Cu" "F.Mask" "F.Paste")
			(net "GND")
		)
	)
	(footprint ""
		(layer "F.Cu")
		(at 326.743568 -408.517344 -90)
		(property "Reference" "C916"
			(at 0 0 270)
			(layer "F.SilkS")
			(hide yes)
			(effects
				(font
					(size 1.27 1.27)
				)
			)
		)
		(property "Value" ""
			(at 0 0 270)
			(layer "F.Fab")
			(effects
				(font
					(size 1.27 1.27)
				)
			)
		)
		(duplicate_pad_numbers_are_jumpers no)
		(fp_line
			(start -0.299974 0.150114)
			(end -0.299974 -0.150114)
			(stroke
				(width 0.1)
				(type default)
			)
			(layer "F.Fab")
		)
		(fp_line
			(start 0.299974 0.150114)
			(end -0.299974 0.150114)
			(stroke
				(width 0.1)
				(type default)
			)
			(layer "F.Fab")
		)
		(fp_line
			(start -0.299974 -0.150114)
			(end 0.299974 -0.150114)
			(stroke
				(width 0.1)
				(type default)
			)
			(layer "F.Fab")
		)
		(fp_line
			(start 0.299974 -0.150114)
			(end 0.299974 0.150114)
			(stroke
				(width 0.1)
				(type default)
			)
			(layer "F.Fab")
		)
		(pad "1" smd rect
			(at -0.2667 0 270)
			(size 0.3048 0.381)
			(layers "F.Cu" "F.Mask" "F.Paste")
			(net "P5E_CPU0_PE0_TX_C_DN<8>")
		)
		(pad "2" smd rect
			(at 0.2667 0 270)
			(size 0.3048 0.381)
			(layers "F.Cu" "F.Mask" "F.Paste")
			(net "P5E_CPU0_PE0_TX_DN<8>")
		)
	)
	(footprint ""
		(layer "F.Cu")
		(at 364.50143 -256.654046 -90)
		(property "Reference" "C984"
			(at 0 0 270)
			(layer "F.SilkS")
			(hide yes)
			(effects
				(font
					(size 1.27 1.27)
				)
			)
		)
		(property "Value" ""
			(at 0 0 270)
			(layer "F.Fab")
			(effects
				(font
					(size 1.27 1.27)
				)
			)
		)
		(duplicate_pad_numbers_are_jumpers no)
		(fp_line
			(start -0.7874 0.4064)
			(end -0.7874 -0.4064)
			(stroke
				(width 0.1524)
				(type default)
			)
			(layer "F.SilkS")
		)
		(fp_line
			(start 0.7874 0.4064)
			(end -0.7874 0.4064)
			(stroke
				(width 0.1524)
				(type default)
			)
			(layer "F.SilkS")
		)
		(fp_line
			(start -0.7874 -0.4064)
			(end 0.7874 -0.4064)
			(stroke
				(width 0.1524)
				(type default)
			)
			(layer "F.SilkS")
		)
		(fp_line
			(start 0.7874 -0.4064)
			(end 0.7874 0.4064)
			(stroke
				(width 0.1524)
				(type default)
			)
			(layer "F.SilkS")
		)
		(fp_line
			(start -0.67945 0.3048)
			(end -0.67945 -0.305054)
			(stroke
				(width 0.1)
				(type default)
			)
			(layer "F.Fab")
		)
		(fp_line
			(start -0.12065 0.3048)
			(end -0.67945 0.3048)
			(stroke
				(width 0.1)
				(type default)
			)
			(layer "F.Fab")
		)
		(fp_line
			(start 0.120396 0.3048)
			(end 0.120396 0.2794)
			(stroke
				(width 0.1)
				(type default)
			)
			(layer "F.Fab")
		)
		(fp_line
			(start 0.67945 0.3048)
			(end 0.120396 0.3048)
			(stroke
				(width 0.1)
				(type default)
			)
			(layer "F.Fab")
		)
		(fp_line
			(start -0.12065 0.2794)
			(end -0.12065 0.3048)
			(stroke
				(width 0.1)
				(type default)
			)
			(layer "F.Fab")
		)
		(fp_line
			(start 0.120396 0.2794)
			(end -0.12065 0.2794)
			(stroke
				(width 0.1)
				(type default)
			)
			(layer "F.Fab")
		)
		(fp_line
			(start -0.12065 -0.2794)
			(end 0.12065 -0.2794)
			(stroke
				(width 0.1)
				(type default)
			)
			(layer "F.Fab")
		)
		(fp_line
			(start 0.12065 -0.2794)
			(end 0.12065 -0.3048)
			(stroke
				(width 0.1)
				(type default)
			)
			(layer "F.Fab")
		)
		(fp_line
			(start 0.12065 -0.3048)
			(end 0.67945 -0.3048)
			(stroke
				(width 0.1)
				(type default)
			)
			(layer "F.Fab")
		)
		(fp_line
			(start 0.67945 -0.3048)
			(end 0.67945 0.3048)
			(stroke
				(width 0.1)
				(type default)
			)
			(layer "F.Fab")
		)
		(fp_line
			(start -0.67945 -0.305054)
			(end -0.12065 -0.305054)
			(stroke
				(width 0.1)
				(type default)
			)
			(layer "F.Fab")
		)
		(fp_line
			(start -0.12065 -0.305054)
			(end -0.12065 -0.2794)
			(stroke
				(width 0.1)
				(type default)
			)
			(layer "F.Fab")
		)
		(pad "1" smd circle
			(at -0.40005 0 270)
			(size 0 0)
			(layers "F.Cu" "F.Mask" "F.Paste")
			(net "PVCCIN_CPU0")
		)
		(pad "2" smd circle
			(at 0.40005 0 270)
			(size 0 0)
			(layers "F.Cu" "F.Mask" "F.Paste")
			(net "GND")
		)
	)
)
